(kicad_pcb
	(version 20260206)
	(generator "pcbnew")
	(generator_version "10.0")
	(general
		(thickness 1.6)
		(legacy_teardrops no)
	)
	(paper "A4")
	(title_block
		(title "v1-chassis-manager — T6M_CM_d_v01_1031_1645.brd")
		(comment 1 "Open CloudServer (Microsoft) / footprints 388-394 of 2512")
	)
	(layers
		(0 "F.Cu" signal "TOP")
		(4 "In1.Cu" signal "GND1")
		(6 "In2.Cu" signal "IN1")
		(8 "In3.Cu" signal "VCC1")
		(10 "In4.Cu" signal "VCC2")
		(12 "In5.Cu" signal "GND2")
		(14 "In6.Cu" signal "IN2")
		(16 "In7.Cu" signal "IN3")
		(18 "In8.Cu" signal "GND3")
		(2 "B.Cu" signal "BOTTOM")
		(9 "F.Adhes" user "F.Adhesive")
		(11 "B.Adhes" user "B.Adhesive")
		(13 "F.Paste" user "Package Geometry/Pastemask Top")
		(15 "B.Paste" user "Package Geometry/Pastemask Bottom")
		(5 "F.SilkS" user "Ref Des/Silkscreen Top")
		(7 "B.SilkS" user "Ref Des/Silkscreen Bottom")
		(1 "F.Mask" user "Board Geometry/Soldermask Top")
		(3 "B.Mask" user "Board Geometry/Soldermask Bottom")
		(17 "Dwgs.User" user "User.Drawings")
		(19 "Cmts.User" user "User.Comments")
		(21 "Eco1.User" user "User.Eco1")
		(23 "Eco2.User" user "User.Eco2")
		(25 "Edge.Cuts" user "Board Geometry/Outline")
		(27 "Margin" user)
		(31 "F.CrtYd" user "Package Geometry/Place Bound Top")
		(29 "B.CrtYd" user "Package Geometry/Place Bound Bottom")
		(35 "F.Fab" user "Ref Des/Assembly Top")
		(33 "B.Fab" user "Ref Des/Assembly Bottom")
	)
	(footprint ""
		(layer "F.Cu")
		(at 96.338644 -136.238488)
		(property "Reference" "U119"
			(at -3.788918 1.90881 90)
			(unlocked yes)
			(layer "F.SilkS")
			(effects
				(font
					(size 0.635 0.4064)
					(thickness 0.1524)
				)
				(justify left)
			)
		)
		(property "Value" ""
			(at 0 0 0)
			(layer "F.Fab")
			(effects
				(font
					(size 1.27 1.27)
				)
			)
		)
		(duplicate_pad_numbers_are_jumpers no)
		(fp_line
			(start -2.525014 0.025146)
			(end -2.525014 0.661162)
			(stroke
				(width 0.1524)
				(type default)
			)
			(layer "F.SilkS")
		)
		(fp_line
			(start -2.525014 2.540762)
			(end -2.525014 3.075178)
			(stroke
				(width 0.1524)
				(type default)
			)
			(layer "F.SilkS")
		)
		(fp_line
			(start -2.525014 3.075178)
			(end -2.525014 0.025146)
			(stroke
				(width 0.1524)
				(type default)
			)
			(layer "F.SilkS")
		)
		(fp_line
			(start -2.525014 3.075178)
			(end -2.320798 3.075178)
			(stroke
				(width 0.1524)
				(type default)
			)
			(layer "F.SilkS")
		)
		(fp_line
			(start -2.320798 0.025146)
			(end -2.525014 0.025146)
			(stroke
				(width 0.1524)
				(type default)
			)
			(layer "F.SilkS")
		)
		(fp_line
			(start 0.320802 3.075178)
			(end 0.525018 3.075178)
			(stroke
				(width 0.1524)
				(type default)
			)
			(layer "F.SilkS")
		)
		(fp_line
			(start 0.525018 0.025146)
			(end 0.320802 0.025146)
			(stroke
				(width 0.1524)
				(type default)
			)
			(layer "F.SilkS")
		)
		(fp_line
			(start 0.525018 0.686562)
			(end 0.525018 0.025146)
			(stroke
				(width 0.1524)
				(type default)
			)
			(layer "F.SilkS")
		)
		(fp_line
			(start 0.525018 3.075178)
			(end 0.525018 0.025146)
			(stroke
				(width 0.1524)
				(type default)
			)
			(layer "F.SilkS")
		)
		(fp_line
			(start 0.525018 3.075178)
			(end 0.525018 2.489962)
			(stroke
				(width 0.1524)
				(type default)
			)
			(layer "F.SilkS")
		)
		(fp_poly
			(pts
				(xy 0 -0.519938) (xy 0.299974 -1.420114) (xy -0.299974 -1.420114)
			)
			(stroke
				(width 0)
				(type default)
			)
			(fill yes)
			(layer "F.SilkS")
		)
		(fp_poly
			(pts
				(xy 0.525018 0.025146) (xy 0.244602 0.025146) (xy 0.244602 -0.532638) (xy -2.244598 -0.532638) (xy -2.244598 0.025146)
				(xy -2.525014 0.025146) (xy -2.525014 3.075178) (xy -2.244598 3.075178) (xy -2.244598 3.632962)
				(xy 0.244602 3.632962) (xy 0.244602 3.075178) (xy 0.525018 3.075178)
			)
			(stroke
				(width 0)
				(type default)
			)
			(fill no)
			(layer "F.CrtYd")
		)
		(fp_line
			(start -2.525014 0.025146)
			(end 0.525018 0.025146)
			(stroke
				(width 0.1)
				(type default)
			)
			(layer "F.Fab")
		)
		(fp_line
			(start -2.525014 3.075178)
			(end -2.525014 0.025146)
			(stroke
				(width 0.1)
				(type default)
			)
			(layer "F.Fab")
		)
		(fp_line
			(start 0.525018 0.025146)
			(end 0.525018 3.075178)
			(stroke
				(width 0.1)
				(type default)
			)
			(layer "F.Fab")
		)
		(fp_line
			(start 0.525018 3.075178)
			(end -2.525014 3.075178)
			(stroke
				(width 0.1)
				(type default)
			)
			(layer "F.Fab")
		)
		(fp_poly
			(pts
				(xy 0 -0.519938) (xy 0.302514 -1.427734) (xy -0.302514 -1.427734)
			)
			(stroke
				(width 0)
				(type default)
			)
			(fill yes)
			(layer "F.Fab")
		)
		(fp_text user "6"
			(at -3.643884 2.99974 0)
			(unlocked yes)
			(layer "F.SilkS")
			(effects
				(font
					(size 0.7874 0.5842)
					(thickness 0.1524)
				)
				(justify left)
			)
		)
		(fp_text user "5"
			(at -2.589784 -0.674878 0)
			(unlocked yes)
			(layer "F.SilkS")
			(effects
				(font
					(size 0.635 0.4064)
					(thickness 0.1524)
				)
				(justify left)
			)
		)
		(fp_text user "10"
			(at 0.119888 3.764026 0)
			(unlocked yes)
			(layer "F.SilkS")
			(effects
				(font
					(size 0.635 0.4064)
					(thickness 0.1524)
				)
				(justify left)
			)
		)
		(fp_text user "1"
			(at 0.160274 -0.722376 0)
			(unlocked yes)
			(layer "F.SilkS")
			(effects
				(font
					(size 0.7874 0.5842)
					(thickness 0.1524)
				)
				(justify left)
			)
		)
		(fp_text user "5"
			(at -2.155698 -0.695706 180)
			(unlocked yes)
			(layer "F.Fab")
			(effects
				(font
					(size 0.7874 0.5842)
					(thickness 0.000001)
				)
				(justify left)
			)
		)
		(fp_text user "6"
			(at -2.155698 3.725672 180)
			(unlocked yes)
			(layer "F.Fab")
			(effects
				(font
					(size 0.7874 0.5842)
					(thickness 0.000001)
				)
				(justify left)
			)
		)
		(fp_text user "1"
			(at 0.790702 -0.695706 180)
			(unlocked yes)
			(layer "F.Fab")
			(effects
				(font
					(size 0.7874 0.5842)
					(thickness 0.000001)
				)
				(justify left)
			)
		)
		(fp_text user "10"
			(at 1.565402 3.700272 180)
			(unlocked yes)
			(layer "F.Fab")
			(effects
				(font
					(size 0.7874 0.5842)
					(thickness 0.000001)
				)
				(justify left)
			)
		)
		(pad "1" smd rect
			(at 0 0 180)
			(size 0.2794 0.9144)
			(layers "F.Cu" "F.Mask" "F.Paste")
			(net "P1V05_SUS_NODE1")
		)
		(pad "2" smd rect
			(at -0.499872 0 180)
			(size 0.2794 0.9144)
			(layers "F.Cu" "F.Mask" "F.Paste")
			(net "P1V05_SUS_NODE1")
		)
		(pad "3" smd rect
			(at -0.999998 0 180)
			(size 0.2794 0.9144)
			(layers "F.Cu" "F.Mask" "F.Paste")
			(net "P1V05_SUS_NODE1")
		)
		(pad "4" smd rect
			(at -1.500124 0 180)
			(size 0.2794 0.9144)
			(layers "F.Cu" "F.Mask" "F.Paste")
			(net "P1V05_SUS_NODE1_ADJ")
		)
		(pad "5" smd rect
			(at -1.999996 0)
			(size 0.2794 0.9144)
			(layers "F.Cu" "F.Mask" "F.Paste")
			(net "PWRGD_NODE1_P1V05_SUS_PG")
		)
		(pad "6" smd rect
			(at -1.999996 3.100324)
			(size 0.2794 0.9144)
			(layers "F.Cu" "F.Mask" "F.Paste")
			(net "FM_CPLD_NODE1_P1V05_SUS_EN")
		)
		(pad "7" smd rect
			(at -1.500124 3.100324 180)
			(size 0.2794 0.9144)
			(layers "F.Cu" "F.Mask" "F.Paste")
			(net "P1V8_STB_NODE1")
		)
		(pad "8" smd rect
			(at -0.999998 3.100324 180)
			(size 0.2794 0.9144)
			(layers "F.Cu" "F.Mask" "F.Paste")
			(net "P1V8_STB_NODE1")
		)
		(pad "9" smd rect
			(at -0.499872 3.100324 180)
			(size 0.2794 0.9144)
			(layers "F.Cu" "F.Mask" "F.Paste")
			(net "P1V8_STB_NODE1")
		)
		(pad "10" smd rect
			(at 0 3.100324 180)
			(size 0.2794 0.9144)
			(layers "F.Cu" "F.Mask" "F.Paste")
			(net "P5V_STB_NODE1")
		)
		(pad "TH" smd rect
			(at -0.999998 1.550162 270)
			(size 1.7526 2.667)
			(layers "F.Cu" "F.Mask" "F.Paste")
			(net "GND")
		)
		(zone
			(layer "F.Cu")
			(hatch none 0.5)
			(connect_pads
				(clearance 0)
			)
			(min_thickness 0.25)
			(keepout
				(tracks allowed)
				(vias not_allowed)
				(pads allowed)
				(copperpour not_allowed)
				(footprints allowed)
			)
			(placement
				(enabled no)
				(sheetname "")
			)
			(fill
				(thermal_gap 0.5)
				(thermal_bridge_width 0.5)
				(island_removal_mode 0)
			)
			(polygon
				(pts
					(xy 96.872044 -135.705088) (xy 93.824044 -135.705088) (xy 93.824044 -133.673088) (xy 96.872044 -133.673088)
					(xy 96.872044 -135.603488) (xy 96.745044 -135.603488) (xy 96.745044 -133.749288) (xy 93.925644 -133.749288)
					(xy 93.925644 -135.628888) (xy 96.872044 -135.628888)
				)
			)
		)
	)
	(footprint ""
		(layer "F.Cu")
		(at 152.76576 -188.126624 90)
		(property "Reference" "C666"
			(at 5.519674 -3.062732 90)
			(unlocked yes)
			(layer "F.SilkS")
			(effects
				(font
					(size 0.7874 0.5842)
					(thickness 0.1524)
				)
				(justify left)
			)
		)
		(property "Value" ""
			(at 0 0 90)
			(layer "F.Fab")
			(effects
				(font
					(size 1.27 1.27)
				)
			)
		)
		(duplicate_pad_numbers_are_jumpers no)
		(fp_line
			(start 0.7874 -0.4064)
			(end 0.7874 0.4064)
			(stroke
				(width 0.1524)
				(type default)
			)
			(layer "F.SilkS")
		)
		(fp_line
			(start -0.7874 -0.4064)
			(end 0.7874 -0.4064)
			(stroke
				(width 0.1524)
				(type default)
			)
			(layer "F.SilkS")
		)
		(fp_line
			(start 0 0.381)
			(end 0 -0.381)
			(stroke
				(width 0.1524)
				(type default)
			)
			(layer "F.SilkS")
		)
		(fp_line
			(start 0.7874 0.4064)
			(end -0.7874 0.4064)
			(stroke
				(width 0.1524)
				(type default)
			)
			(layer "F.SilkS")
		)
		(fp_line
			(start -0.7874 0.4064)
			(end -0.7874 -0.4064)
			(stroke
				(width 0.1524)
				(type default)
			)
			(layer "F.SilkS")
		)
		(fp_poly
			(pts
				(xy -0.5334 0.254) (xy -0.635 0.254) (xy -0.635 0.2286) (xy -0.635 -0.254) (xy -0.5334 -0.254) (xy -0.5334 -0.2794)
				(xy 0.5334 -0.2794) (xy 0.5334 -0.254) (xy 0.635 -0.254) (xy 0.635 0.254) (xy 0.5334 0.254) (xy 0.5334 0.2794)
				(xy -0.508 0.2794) (xy -0.5334 0.2794)
			)
			(stroke
				(width 0)
				(type default)
			)
			(fill no)
			(layer "F.CrtYd")
		)
		(pad "1" smd rect
			(at 0.40005 0 90)
			(size 0.4572 0.508)
			(layers "F.Cu" "F.Mask" "F.Paste")
			(net "T12_NODE3_EN_R")
		)
		(pad "2" smd rect
			(at -0.40005 0 90)
			(size 0.4572 0.508)
			(layers "F.Cu" "F.Mask" "F.Paste")
			(net "GND")
		)
	)
	(footprint ""
		(layer "F.Cu")
		(at 34.976816 -104.248712 90)
		(property "Reference" "R1089"
			(at -6.011672 -0.00381 90)
			(unlocked yes)
			(layer "F.SilkS")
			(effects
				(font
					(size 0.7874 0.5842)
					(thickness 0.1524)
				)
				(justify left)
			)
		)
		(property "Value" ""
			(at 0 0 90)
			(layer "F.Fab")
			(effects
				(font
					(size 1.27 1.27)
				)
			)
		)
		(duplicate_pad_numbers_are_jumpers no)
		(fp_line
			(start 0.7874 -0.4064)
			(end 0.7874 0.4064)
			(stroke
				(width 0.1524)
				(type default)
			)
			(layer "F.SilkS")
		)
		(fp_line
			(start -0.7874 -0.4064)
			(end 0.7874 -0.4064)
			(stroke
				(width 0.1524)
				(type default)
			)
			(layer "F.SilkS")
		)
		(fp_line
			(start 0.7874 0.4064)
			(end -0.7874 0.4064)
			(stroke
				(width 0.1524)
				(type default)
			)
			(layer "F.SilkS")
		)
		(fp_line
			(start -0.7874 0.4064)
			(end -0.7874 -0.4064)
			(stroke
				(width 0.1524)
				(type default)
			)
			(layer "F.SilkS")
		)
		(fp_poly
			(pts
				(xy -0.508 0.2794) (xy -0.508 0.2286) (xy -0.635 0.2286) (xy -0.635 -0.254) (xy -0.5334 -0.254)
				(xy -0.5334 -0.2794) (xy 0.5334 -0.2794) (xy 0.5334 -0.254) (xy 0.635 -0.254) (xy 0.635 0.254) (xy 0.5334 0.254)
				(xy 0.5334 0.2794)
			)
			(stroke
				(width 0)
				(type default)
			)
			(fill no)
			(layer "F.CrtYd")
		)
		(pad "1" smd rect
			(at 0.40005 0 90)
			(size 0.4572 0.508)
			(layers "F.Cu" "F.Mask" "F.Paste")
			(net "GND")
		)
		(pad "2" smd rect
			(at -0.40005 0 90)
			(size 0.4572 0.508)
			(layers "F.Cu" "F.Mask" "F.Paste")
			(net "P1V5_SUS_NODE1_ADJ")
		)
	)
	(footprint ""
		(layer "F.Cu")
		(at 80.382364 -17.679416 90)
		(property "Reference" "C145"
			(at -4.546854 5.52323 90)
			(unlocked yes)
			(layer "F.SilkS")
			(effects
				(font
					(size 0.7874 0.5842)
					(thickness 0.1524)
				)
				(justify left)
			)
		)
		(property "Value" ""
			(at 0 0 90)
			(layer "F.Fab")
			(effects
				(font
					(size 1.27 1.27)
				)
			)
		)
		(duplicate_pad_numbers_are_jumpers no)
		(fp_line
			(start 0.7874 -0.4064)
			(end 0.7874 0.4064)
			(stroke
				(width 0.1524)
				(type default)
			)
			(layer "F.SilkS")
		)
		(fp_line
			(start -0.7874 -0.4064)
			(end 0.7874 -0.4064)
			(stroke
				(width 0.1524)
				(type default)
			)
			(layer "F.SilkS")
		)
		(fp_line
			(start 0 0.381)
			(end 0 -0.381)
			(stroke
				(width 0.1524)
				(type default)
			)
			(layer "F.SilkS")
		)
		(fp_line
			(start 0.7874 0.4064)
			(end -0.7874 0.4064)
			(stroke
				(width 0.1524)
				(type default)
			)
			(layer "F.SilkS")
		)
		(fp_line
			(start -0.7874 0.4064)
			(end -0.7874 -0.4064)
			(stroke
				(width 0.1524)
				(type default)
			)
			(layer "F.SilkS")
		)
		(fp_poly
			(pts
				(xy -0.5334 0.254) (xy -0.635 0.254) (xy -0.635 0.2286) (xy -0.635 -0.254) (xy -0.5334 -0.254) (xy -0.5334 -0.2794)
				(xy 0.5334 -0.2794) (xy 0.5334 -0.254) (xy 0.635 -0.254) (xy 0.635 0.254) (xy 0.5334 0.254) (xy 0.5334 0.2794)
				(xy -0.508 0.2794) (xy -0.5334 0.2794)
			)
			(stroke
				(width 0)
				(type default)
			)
			(fill no)
			(layer "F.CrtYd")
		)
		(pad "1" smd rect
			(at 0.40005 0 90)
			(size 0.4572 0.508)
			(layers "F.Cu" "F.Mask" "F.Paste")
			(net "PV_VDDR_NODE1")
		)
		(pad "2" smd rect
			(at -0.40005 0 90)
			(size 0.4572 0.508)
			(layers "F.Cu" "F.Mask" "F.Paste")
			(net "GND")
		)
	)
	(footprint ""
		(layer "F.Cu")
		(at 79.98714 -158.242508 -90)
		(property "Reference" "PR2"
			(at 0.960628 -4.381246 90)
			(unlocked yes)
			(layer "F.SilkS")
			(effects
				(font
					(size 0.7874 0.5842)
					(thickness 0.1524)
				)
				(justify left)
			)
		)
		(property "Value" ""
			(at 0 0 270)
			(layer "F.Fab")
			(effects
				(font
					(size 1.27 1.27)
				)
			)
		)
		(duplicate_pad_numbers_are_jumpers no)
		(fp_line
			(start -0.7874 0.4064)
			(end -0.7874 -0.4064)
			(stroke
				(width 0.1524)
				(type default)
			)
			(layer "F.SilkS")
		)
		(fp_line
			(start 0.7874 0.4064)
			(end -0.7874 0.4064)
			(stroke
				(width 0.1524)
				(type default)
			)
			(layer "F.SilkS")
		)
		(fp_line
			(start -0.7874 -0.4064)
			(end 0.7874 -0.4064)
			(stroke
				(width 0.1524)
				(type default)
			)
			(layer "F.SilkS")
		)
		(fp_line
			(start 0.7874 -0.4064)
			(end 0.7874 0.4064)
			(stroke
				(width 0.1524)
				(type default)
			)
			(layer "F.SilkS")
		)
		(fp_poly
			(pts
				(xy -0.508 0.2794) (xy -0.508 0.2286) (xy -0.635 0.2286) (xy -0.635 -0.254) (xy -0.5334 -0.254)
				(xy -0.5334 -0.2794) (xy 0.5334 -0.2794) (xy 0.5334 -0.254) (xy 0.635 -0.254) (xy 0.635 0.254) (xy 0.5334 0.254)
				(xy 0.5334 0.2794)
			)
			(stroke
				(width 0)
				(type default)
			)
			(fill no)
			(layer "F.CrtYd")
		)
		(pad "1" smd rect
			(at 0.40005 0 270)
			(size 0.4572 0.508)
			(layers "F.Cu" "F.Mask" "F.Paste")
			(net "PWRGD_NODE1_P5V_STB_PG")
		)
		(pad "2" smd rect
			(at -0.40005 0 270)
			(size 0.4572 0.508)
			(layers "F.Cu" "F.Mask" "F.Paste")
			(net "GND")
		)
	)
	(footprint ""
		(layer "F.Cu")
		(at 153.439114 -89.199466 -90)
		(property "Reference" "R530"
			(at -0.437134 3.434588 0)
			(unlocked yes)
			(layer "F.SilkS")
			(effects
				(font
					(size 0.7874 0.5842)
					(thickness 0.1524)
				)
				(justify left)
			)
		)
		(property "Value" ""
			(at 0 0 270)
			(layer "F.Fab")
			(effects
				(font
					(size 1.27 1.27)
				)
			)
		)
		(duplicate_pad_numbers_are_jumpers no)
		(fp_line
			(start -0.7874 0.4064)
			(end -0.7874 -0.4064)
			(stroke
				(width 0.1524)
				(type default)
			)
			(layer "F.SilkS")
		)
		(fp_line
			(start 0.7874 0.4064)
			(end -0.7874 0.4064)
			(stroke
				(width 0.1524)
				(type default)
			)
			(layer "F.SilkS")
		)
		(fp_line
			(start -0.7874 -0.4064)
			(end 0.7874 -0.4064)
			(stroke
				(width 0.1524)
				(type default)
			)
			(layer "F.SilkS")
		)
		(fp_line
			(start 0.7874 -0.4064)
			(end 0.7874 0.4064)
			(stroke
				(width 0.1524)
				(type default)
			)
			(layer "F.SilkS")
		)
		(fp_poly
			(pts
				(xy -0.508 0.2794) (xy -0.508 0.2286) (xy -0.635 0.2286) (xy -0.635 -0.254) (xy -0.5334 -0.254)
				(xy -0.5334 -0.2794) (xy 0.5334 -0.2794) (xy 0.5334 -0.254) (xy 0.635 -0.254) (xy 0.635 0.254) (xy 0.5334 0.254)
				(xy 0.5334 0.2794)
			)
			(stroke
				(width 0)
				(type default)
			)
			(fill no)
			(layer "F.CrtYd")
		)
		(pad "1" smd rect
			(at 0.40005 0 270)
			(size 0.4572 0.508)
			(layers "F.Cu" "F.Mask" "F.Paste")
			(net "SPI_USB_NODE1_SI_R")
		)
		(pad "2" smd rect
			(at -0.40005 0 270)
			(size 0.4572 0.508)
			(layers "F.Cu" "F.Mask" "F.Paste")
			(net "SPI_USB_NODE1_SI")
		)
	)
	(footprint ""
		(layer "F.Cu")
		(at 165.011354 -182.035196 180)
		(property "Reference" "R1169"
			(at 5.214366 -0.616966 0)
			(unlocked yes)
			(layer "F.SilkS")
			(effects
				(font
					(size 0.7874 0.5842)
					(thickness 0.1524)
				)
				(justify left)
			)
		)
		(property "Value" ""
			(at 0 0 180)
			(layer "F.Fab")
			(effects
				(font
					(size 1.27 1.27)
				)
			)
		)
		(duplicate_pad_numbers_are_jumpers no)
		(fp_line
			(start 0.7874 0.406146)
			(end -0.7874 0.406146)
			(stroke
				(width 0.1524)
				(type default)
			)
			(layer "F.SilkS")
		)
		(fp_line
			(start 0.7874 -0.406146)
			(end 0.7874 0.406146)
			(stroke
				(width 0.1524)
				(type default)
			)
			(layer "F.SilkS")
		)
		(fp_line
			(start -0.7874 0.406146)
			(end -0.7874 -0.406146)
			(stroke
				(width 0.1524)
				(type default)
			)
			(layer "F.SilkS")
		)
		(fp_line
			(start -0.7874 -0.406146)
			(end 0.7874 -0.406146)
			(stroke
				(width 0.1524)
				(type default)
			)
			(layer "F.SilkS")
		)
		(fp_poly
			(pts
				(xy -0.508 0.2794) (xy -0.508 0.2286) (xy -0.635 0.2286) (xy -0.635 -0.254) (xy -0.5334 -0.254)
				(xy -0.5334 -0.2794) (xy 0.5334 -0.2794) (xy 0.5334 -0.254) (xy 0.635 -0.254) (xy 0.635 0.254) (xy 0.5334 0.254)
				(xy 0.5334 0.2794)
			)
			(stroke
				(width 0)
				(type default)
			)
			(fill no)
			(layer "F.CrtYd")
		)
		(pad "1" smd rect
			(at 0.40005 0 180)
			(size 0.4572 0.508)
			(layers "F.Cu" "F.Mask" "F.Paste")
			(net "CPLD_UART_RTS_P3_R_N")
		)
		(pad "2" smd rect
			(at -0.40005 0 180)
			(size 0.4572 0.508)
			(layers "F.Cu" "F.Mask" "F.Paste")
			(net "CPLD_UART_RTS_P3_N")
		)
	)
)
